(kicad_pcb
	(version 20260206)
	(generator "pcbnew")
	(generator_version "10.0")
	(general
		(thickness 1.6)
		(legacy_teardrops no)
	)
	(paper "A4")
	(title_block
		(title "01162023_DA0F0TEBIF0_F0T_Expander_BD_F_brd_V02_OCP.brd")
		(comment 1 "Grand Teton / footprints 6157-6163 of 9728")
	)
	(layers
		(0 "F.Cu" signal "TOP")
		(4 "In1.Cu" signal "GND")
		(6 "In2.Cu" signal "VCC")
		(8 "In3.Cu" signal "VCC1")
		(10 "In4.Cu" signal "GND1")
		(12 "In5.Cu" signal "IN1")
		(14 "In6.Cu" signal "GND2")
		(16 "In7.Cu" signal "IN2")
		(18 "In8.Cu" signal "GND3")
		(20 "In9.Cu" signal "IN3")
		(22 "In10.Cu" signal "GND4")
		(24 "In11.Cu" signal "IN4")
		(26 "In12.Cu" signal "GND5")
		(28 "In13.Cu" signal "IN5")
		(30 "In14.Cu" signal "GND6")
		(32 "In15.Cu" signal "IN6")
		(34 "In16.Cu" signal "GND7")
		(2 "B.Cu" signal "BOTTOM")
		(9 "F.Adhes" user "F.Adhesive")
		(11 "B.Adhes" user "B.Adhesive")
		(13 "F.Paste" user "Package Geometry/Pastemask Top")
		(15 "B.Paste" user "Package Geometry/Pastemask Bottom")
		(5 "F.SilkS" user "Ref Des/Silkscreen Top")
		(7 "B.SilkS" user "Ref Des/Silkscreen Bottom")
		(1 "F.Mask" user "Board Geometry/Soldermask Top")
		(3 "B.Mask" user "Board Geometry/Soldermask Bottom")
		(17 "Dwgs.User" user "User.Drawings")
		(19 "Cmts.User" user "User.Comments")
		(21 "Eco1.User" user "User.Eco1")
		(23 "Eco2.User" user "User.Eco2")
		(25 "Edge.Cuts" user "Board Geometry/Outline")
		(27 "Margin" user)
		(31 "F.CrtYd" user "Package Geometry/Place Bound Top")
		(29 "B.CrtYd" user "Package Geometry/Place Bound Bottom")
		(35 "F.Fab" user "Ref Des/Assembly Top")
		(33 "B.Fab" user "Ref Des/Assembly Bottom")
	)
	(footprint ""
		(layer "F.Cu")
		(at 168.343834 -45.88891)
		(property "Reference" "R564"
			(at 0 0 0)
			(layer "F.SilkS")
			(hide yes)
			(effects
				(font
					(size 1.27 1.27)
				)
			)
		)
		(property "Value" ""
			(at 0 0 0)
			(layer "F.Fab")
			(effects
				(font
					(size 1.27 1.27)
				)
			)
		)
		(duplicate_pad_numbers_are_jumpers no)
		(fp_line
			(start -0.7874 -0.4064)
			(end 0.7874 -0.4064)
			(stroke
				(width 0.1524)
				(type default)
			)
			(layer "F.SilkS")
		)
		(fp_line
			(start -0.7874 0.4064)
			(end -0.7874 -0.4064)
			(stroke
				(width 0.1524)
				(type default)
			)
			(layer "F.SilkS")
		)
		(fp_line
			(start 0.7874 -0.4064)
			(end 0.7874 0.4064)
			(stroke
				(width 0.1524)
				(type default)
			)
			(layer "F.SilkS")
		)
		(fp_line
			(start 0.7874 0.4064)
			(end -0.7874 0.4064)
			(stroke
				(width 0.1524)
				(type default)
			)
			(layer "F.SilkS")
		)
		(fp_line
			(start -0.67945 -0.305054)
			(end -0.12065 -0.305054)
			(stroke
				(width 0.1)
				(type default)
			)
			(layer "F.Fab")
		)
		(fp_line
			(start -0.67945 0.3048)
			(end -0.67945 -0.305054)
			(stroke
				(width 0.1)
				(type default)
			)
			(layer "F.Fab")
		)
		(fp_line
			(start -0.12065 -0.305054)
			(end -0.12065 -0.2794)
			(stroke
				(width 0.1)
				(type default)
			)
			(layer "F.Fab")
		)
		(fp_line
			(start -0.12065 -0.2794)
			(end 0.12065 -0.2794)
			(stroke
				(width 0.1)
				(type default)
			)
			(layer "F.Fab")
		)
		(fp_line
			(start -0.12065 0.2794)
			(end -0.12065 0.3048)
			(stroke
				(width 0.1)
				(type default)
			)
			(layer "F.Fab")
		)
		(fp_line
			(start -0.12065 0.3048)
			(end -0.67945 0.3048)
			(stroke
				(width 0.1)
				(type default)
			)
			(layer "F.Fab")
		)
		(fp_line
			(start 0.120396 0.2794)
			(end -0.12065 0.2794)
			(stroke
				(width 0.1)
				(type default)
			)
			(layer "F.Fab")
		)
		(fp_line
			(start 0.120396 0.3048)
			(end 0.120396 0.2794)
			(stroke
				(width 0.1)
				(type default)
			)
			(layer "F.Fab")
		)
		(fp_line
			(start 0.12065 -0.3048)
			(end 0.67945 -0.3048)
			(stroke
				(width 0.1)
				(type default)
			)
			(layer "F.Fab")
		)
		(fp_line
			(start 0.12065 -0.2794)
			(end 0.12065 -0.3048)
			(stroke
				(width 0.1)
				(type default)
			)
			(layer "F.Fab")
		)
		(fp_line
			(start 0.67945 -0.3048)
			(end 0.67945 0.3048)
			(stroke
				(width 0.1)
				(type default)
			)
			(layer "F.Fab")
		)
		(fp_line
			(start 0.67945 0.3048)
			(end 0.120396 0.3048)
			(stroke
				(width 0.1)
				(type default)
			)
			(layer "F.Fab")
		)
		(pad "1" smd circle
			(at -0.40005 0)
			(size 0 0)
			(layers "F.Cu" "F.Mask" "F.Paste")
			(net "SSD5_ADC_A0")
		)
		(pad "2" smd circle
			(at 0.40005 0)
			(size 0 0)
			(layers "F.Cu" "F.Mask" "F.Paste")
			(net "GND")
		)
	)
	(footprint ""
		(layer "F.Cu")
		(at 144.554956 -22.961346 90)
		(property "Reference" "R1659"
			(at 0 0 90)
			(layer "F.SilkS")
			(hide yes)
			(effects
				(font
					(size 1.27 1.27)
				)
			)
		)
		(property "Value" ""
			(at 0 0 90)
			(layer "F.Fab")
			(effects
				(font
					(size 1.27 1.27)
				)
			)
		)
		(duplicate_pad_numbers_are_jumpers no)
		(fp_line
			(start 0.7874 -0.4064)
			(end 0.7874 0.4064)
			(stroke
				(width 0.1524)
				(type default)
			)
			(layer "F.SilkS")
		)
		(fp_line
			(start -0.7874 -0.4064)
			(end 0.7874 -0.4064)
			(stroke
				(width 0.1524)
				(type default)
			)
			(layer "F.SilkS")
		)
		(fp_line
			(start 0.7874 0.4064)
			(end -0.7874 0.4064)
			(stroke
				(width 0.1524)
				(type default)
			)
			(layer "F.SilkS")
		)
		(fp_line
			(start -0.7874 0.4064)
			(end -0.7874 -0.4064)
			(stroke
				(width 0.1524)
				(type default)
			)
			(layer "F.SilkS")
		)
		(fp_line
			(start -0.12065 -0.305054)
			(end -0.12065 -0.2794)
			(stroke
				(width 0.1)
				(type default)
			)
			(layer "F.Fab")
		)
		(fp_line
			(start -0.67945 -0.305054)
			(end -0.12065 -0.305054)
			(stroke
				(width 0.1)
				(type default)
			)
			(layer "F.Fab")
		)
		(fp_line
			(start 0.67945 -0.3048)
			(end 0.67945 0.3048)
			(stroke
				(width 0.1)
				(type default)
			)
			(layer "F.Fab")
		)
		(fp_line
			(start 0.12065 -0.3048)
			(end 0.67945 -0.3048)
			(stroke
				(width 0.1)
				(type default)
			)
			(layer "F.Fab")
		)
		(fp_line
			(start 0.12065 -0.2794)
			(end 0.12065 -0.3048)
			(stroke
				(width 0.1)
				(type default)
			)
			(layer "F.Fab")
		)
		(fp_line
			(start -0.12065 -0.2794)
			(end 0.12065 -0.2794)
			(stroke
				(width 0.1)
				(type default)
			)
			(layer "F.Fab")
		)
		(fp_line
			(start 0.120396 0.2794)
			(end -0.12065 0.2794)
			(stroke
				(width 0.1)
				(type default)
			)
			(layer "F.Fab")
		)
		(fp_line
			(start -0.12065 0.2794)
			(end -0.12065 0.3048)
			(stroke
				(width 0.1)
				(type default)
			)
			(layer "F.Fab")
		)
		(fp_line
			(start 0.67945 0.3048)
			(end 0.120396 0.3048)
			(stroke
				(width 0.1)
				(type default)
			)
			(layer "F.Fab")
		)
		(fp_line
			(start 0.120396 0.3048)
			(end 0.120396 0.2794)
			(stroke
				(width 0.1)
				(type default)
			)
			(layer "F.Fab")
		)
		(fp_line
			(start -0.12065 0.3048)
			(end -0.67945 0.3048)
			(stroke
				(width 0.1)
				(type default)
			)
			(layer "F.Fab")
		)
		(fp_line
			(start -0.67945 0.3048)
			(end -0.67945 -0.305054)
			(stroke
				(width 0.1)
				(type default)
			)
			(layer "F.Fab")
		)
		(pad "1" smd circle
			(at -0.40005 0 90)
			(size 0 0)
			(layers "F.Cu" "F.Mask" "F.Paste")
			(net "SMB_SSD4_ISO_EN")
		)
		(pad "2" smd circle
			(at 0.40005 0 90)
			(size 0 0)
			(layers "F.Cu" "F.Mask" "F.Paste")
			(net "P3V3_AUX")
		)
	)
	(footprint ""
		(layer "F.Cu")
		(at 171.929044 -116.5352 180)
		(property "Reference" "R142"
			(at 0 0 180)
			(layer "F.SilkS")
			(hide yes)
			(effects
				(font
					(size 1.27 1.27)
				)
			)
		)
		(property "Value" ""
			(at 0 0 180)
			(layer "F.Fab")
			(effects
				(font
					(size 1.27 1.27)
				)
			)
		)
		(duplicate_pad_numbers_are_jumpers no)
		(fp_line
			(start 0.7874 0.4064)
			(end -0.7874 0.4064)
			(stroke
				(width 0.1524)
				(type default)
			)
			(layer "F.SilkS")
		)
		(fp_line
			(start 0.7874 -0.4064)
			(end 0.7874 0.4064)
			(stroke
				(width 0.1524)
				(type default)
			)
			(layer "F.SilkS")
		)
		(fp_line
			(start -0.7874 0.4064)
			(end -0.7874 -0.4064)
			(stroke
				(width 0.1524)
				(type default)
			)
			(layer "F.SilkS")
		)
		(fp_line
			(start -0.7874 -0.4064)
			(end 0.7874 -0.4064)
			(stroke
				(width 0.1524)
				(type default)
			)
			(layer "F.SilkS")
		)
		(fp_line
			(start 0.67945 0.3048)
			(end 0.120396 0.3048)
			(stroke
				(width 0.1)
				(type default)
			)
			(layer "F.Fab")
		)
		(fp_line
			(start 0.67945 -0.3048)
			(end 0.67945 0.3048)
			(stroke
				(width 0.1)
				(type default)
			)
			(layer "F.Fab")
		)
		(fp_line
			(start 0.12065 -0.2794)
			(end 0.12065 -0.3048)
			(stroke
				(width 0.1)
				(type default)
			)
			(layer "F.Fab")
		)
		(fp_line
			(start 0.12065 -0.3048)
			(end 0.67945 -0.3048)
			(stroke
				(width 0.1)
				(type default)
			)
			(layer "F.Fab")
		)
		(fp_line
			(start 0.120396 0.3048)
			(end 0.120396 0.2794)
			(stroke
				(width 0.1)
				(type default)
			)
			(layer "F.Fab")
		)
		(fp_line
			(start 0.120396 0.2794)
			(end -0.12065 0.2794)
			(stroke
				(width 0.1)
				(type default)
			)
			(layer "F.Fab")
		)
		(fp_line
			(start -0.12065 0.3048)
			(end -0.67945 0.3048)
			(stroke
				(width 0.1)
				(type default)
			)
			(layer "F.Fab")
		)
		(fp_line
			(start -0.12065 0.2794)
			(end -0.12065 0.3048)
			(stroke
				(width 0.1)
				(type default)
			)
			(layer "F.Fab")
		)
		(fp_line
			(start -0.12065 -0.2794)
			(end 0.12065 -0.2794)
			(stroke
				(width 0.1)
				(type default)
			)
			(layer "F.Fab")
		)
		(fp_line
			(start -0.12065 -0.305054)
			(end -0.12065 -0.2794)
			(stroke
				(width 0.1)
				(type default)
			)
			(layer "F.Fab")
		)
		(fp_line
			(start -0.67945 0.3048)
			(end -0.67945 -0.305054)
			(stroke
				(width 0.1)
				(type default)
			)
			(layer "F.Fab")
		)
		(fp_line
			(start -0.67945 -0.305054)
			(end -0.12065 -0.305054)
			(stroke
				(width 0.1)
				(type default)
			)
			(layer "F.Fab")
		)
		(pad "1" smd circle
			(at -0.40005 0 180)
			(size 0 0)
			(layers "F.Cu" "F.Mask" "F.Paste")
			(net "PRSNT_NIC2_N")
		)
		(pad "2" smd circle
			(at 0.40005 0 180)
			(size 0 0)
			(layers "F.Cu" "F.Mask" "F.Paste")
			(net "PRSNTB1_NIC2_N")
		)
	)
	(footprint ""
		(layer "F.Cu")
		(at 98.048318 -391.0838)
		(property "Reference" "R5448"
			(at 0 0 0)
			(layer "F.SilkS")
			(hide yes)
			(effects
				(font
					(size 1.27 1.27)
				)
			)
		)
		(property "Value" ""
			(at 0 0 0)
			(layer "F.Fab")
			(effects
				(font
					(size 1.27 1.27)
				)
			)
		)
		(duplicate_pad_numbers_are_jumpers no)
		(fp_line
			(start -0.7874 -0.4064)
			(end 0.7874 -0.4064)
			(stroke
				(width 0.1524)
				(type default)
			)
			(layer "F.SilkS")
		)
		(fp_line
			(start -0.7874 0.4064)
			(end -0.7874 -0.4064)
			(stroke
				(width 0.1524)
				(type default)
			)
			(layer "F.SilkS")
		)
		(fp_line
			(start 0.7874 -0.4064)
			(end 0.7874 0.4064)
			(stroke
				(width 0.1524)
				(type default)
			)
			(layer "F.SilkS")
		)
		(fp_line
			(start 0.7874 0.4064)
			(end -0.7874 0.4064)
			(stroke
				(width 0.1524)
				(type default)
			)
			(layer "F.SilkS")
		)
		(fp_line
			(start -0.67945 -0.305054)
			(end -0.12065 -0.305054)
			(stroke
				(width 0.1)
				(type default)
			)
			(layer "F.Fab")
		)
		(fp_line
			(start -0.67945 0.3048)
			(end -0.67945 -0.305054)
			(stroke
				(width 0.1)
				(type default)
			)
			(layer "F.Fab")
		)
		(fp_line
			(start -0.12065 -0.305054)
			(end -0.12065 -0.2794)
			(stroke
				(width 0.1)
				(type default)
			)
			(layer "F.Fab")
		)
		(fp_line
			(start -0.12065 -0.2794)
			(end 0.12065 -0.2794)
			(stroke
				(width 0.1)
				(type default)
			)
			(layer "F.Fab")
		)
		(fp_line
			(start -0.12065 0.2794)
			(end -0.12065 0.3048)
			(stroke
				(width 0.1)
				(type default)
			)
			(layer "F.Fab")
		)
		(fp_line
			(start -0.12065 0.3048)
			(end -0.67945 0.3048)
			(stroke
				(width 0.1)
				(type default)
			)
			(layer "F.Fab")
		)
		(fp_line
			(start 0.120396 0.2794)
			(end -0.12065 0.2794)
			(stroke
				(width 0.1)
				(type default)
			)
			(layer "F.Fab")
		)
		(fp_line
			(start 0.120396 0.3048)
			(end 0.120396 0.2794)
			(stroke
				(width 0.1)
				(type default)
			)
			(layer "F.Fab")
		)
		(fp_line
			(start 0.12065 -0.3048)
			(end 0.67945 -0.3048)
			(stroke
				(width 0.1)
				(type default)
			)
			(layer "F.Fab")
		)
		(fp_line
			(start 0.12065 -0.2794)
			(end 0.12065 -0.3048)
			(stroke
				(width 0.1)
				(type default)
			)
			(layer "F.Fab")
		)
		(fp_line
			(start 0.67945 -0.3048)
			(end 0.67945 0.3048)
			(stroke
				(width 0.1)
				(type default)
			)
			(layer "F.Fab")
		)
		(fp_line
			(start 0.67945 0.3048)
			(end 0.120396 0.3048)
			(stroke
				(width 0.1)
				(type default)
			)
			(layer "F.Fab")
		)
		(pad "1" smd circle
			(at -0.40005 0)
			(size 0 0)
			(layers "F.Cu" "F.Mask" "F.Paste")
			(net "P3V3_AUX")
		)
		(pad "2" smd circle
			(at 0.40005 0)
			(size 0 0)
			(layers "F.Cu" "F.Mask" "F.Paste")
			(net "BIC_USB_HUB_OVCUR1")
		)
	)
	(footprint ""
		(layer "F.Cu")
		(at 263.898634 -309.570628 45)
		(property "Reference" "R1351"
			(at 0 0 45)
			(layer "F.SilkS")
			(hide yes)
			(effects
				(font
					(size 1.27 1.27)
				)
			)
		)
		(property "Value" ""
			(at 0 0 45)
			(layer "F.Fab")
			(effects
				(font
					(size 1.27 1.27)
				)
			)
		)
		(duplicate_pad_numbers_are_jumpers no)
		(fp_line
			(start -0.787389 -0.406267)
			(end 0.787389 -0.406267)
			(stroke
				(width 0.1524)
				(type default)
			)
			(layer "F.SilkS")
		)
		(fp_line
			(start -0.787389 0.406267)
			(end -0.787389 -0.406267)
			(stroke
				(width 0.1524)
				(type default)
			)
			(layer "F.SilkS")
		)
		(fp_line
			(start 0.787389 -0.406267)
			(end 0.787389 0.406267)
			(stroke
				(width 0.1524)
				(type default)
			)
			(layer "F.SilkS")
		)
		(fp_line
			(start 0.787389 0.406267)
			(end -0.787389 0.406267)
			(stroke
				(width 0.1524)
				(type default)
			)
			(layer "F.SilkS")
		)
		(fp_line
			(start -0.679446 -0.305149)
			(end -0.120695 -0.304969)
			(stroke
				(width 0.1)
				(type default)
			)
			(layer "F.Fab")
		)
		(fp_line
			(start -0.120695 -0.304969)
			(end -0.120695 -0.279466)
			(stroke
				(width 0.1)
				(type default)
			)
			(layer "F.Fab")
		)
		(fp_line
			(start -0.120695 -0.279466)
			(end 0.120695 -0.279466)
			(stroke
				(width 0.1)
				(type default)
			)
			(layer "F.Fab")
		)
		(fp_line
			(start -0.679446 0.30479)
			(end -0.679446 -0.305149)
			(stroke
				(width 0.1)
				(type default)
			)
			(layer "F.Fab")
		)
		(fp_line
			(start 0.120515 -0.30479)
			(end 0.679446 -0.30479)
			(stroke
				(width 0.1)
				(type default)
			)
			(layer "F.Fab")
		)
		(fp_line
			(start 0.120695 -0.279466)
			(end 0.120515 -0.30479)
			(stroke
				(width 0.1)
				(type default)
			)
			(layer "F.Fab")
		)
		(fp_line
			(start -0.120695 0.279466)
			(end -0.120515 0.30479)
			(stroke
				(width 0.1)
				(type default)
			)
			(layer "F.Fab")
		)
		(fp_line
			(start -0.120515 0.30479)
			(end -0.679446 0.30479)
			(stroke
				(width 0.1)
				(type default)
			)
			(layer "F.Fab")
		)
		(fp_line
			(start 0.679446 -0.30479)
			(end 0.679446 0.30479)
			(stroke
				(width 0.1)
				(type default)
			)
			(layer "F.Fab")
		)
		(fp_line
			(start 0.120335 0.279466)
			(end -0.120695 0.279466)
			(stroke
				(width 0.1)
				(type default)
			)
			(layer "F.Fab")
		)
		(fp_line
			(start 0.120515 0.30479)
			(end 0.120335 0.279466)
			(stroke
				(width 0.1)
				(type default)
			)
			(layer "F.Fab")
		)
		(fp_line
			(start 0.679446 0.30479)
			(end 0.120515 0.30479)
			(stroke
				(width 0.1)
				(type default)
			)
			(layer "F.Fab")
		)
		(pad "1" smd circle
			(at -0.40005 0 45)
			(size 0 0)
			(layers "F.Cu" "F.Mask" "F.Paste")
			(net "GND")
		)
		(pad "2" smd circle
			(at 0.40005 0 45)
			(size 0 0)
			(layers "F.Cu" "F.Mask" "F.Paste")
			(net "PEX2_DBG_MODE0")
		)
	)
	(footprint ""
		(layer "F.Cu")
		(at 254.685546 -207.1116 -90)
		(property "Reference" "R5068"
			(at 0 0 270)
			(layer "F.SilkS")
			(hide yes)
			(effects
				(font
					(size 1.27 1.27)
				)
			)
		)
		(property "Value" ""
			(at 0 0 270)
			(layer "F.Fab")
			(effects
				(font
					(size 1.27 1.27)
				)
			)
		)
		(duplicate_pad_numbers_are_jumpers no)
		(fp_line
			(start -0.7874 0.4064)
			(end -0.7874 -0.4064)
			(stroke
				(width 0.1524)
				(type default)
			)
			(layer "F.SilkS")
		)
		(fp_line
			(start 0.7874 0.4064)
			(end -0.7874 0.4064)
			(stroke
				(width 0.1524)
				(type default)
			)
			(layer "F.SilkS")
		)
		(fp_line
			(start -0.7874 -0.4064)
			(end 0.7874 -0.4064)
			(stroke
				(width 0.1524)
				(type default)
			)
			(layer "F.SilkS")
		)
		(fp_line
			(start 0.7874 -0.4064)
			(end 0.7874 0.4064)
			(stroke
				(width 0.1524)
				(type default)
			)
			(layer "F.SilkS")
		)
		(fp_line
			(start -0.67945 0.3048)
			(end -0.67945 -0.305054)
			(stroke
				(width 0.1)
				(type default)
			)
			(layer "F.Fab")
		)
		(fp_line
			(start -0.12065 0.3048)
			(end -0.67945 0.3048)
			(stroke
				(width 0.1)
				(type default)
			)
			(layer "F.Fab")
		)
		(fp_line
			(start 0.120396 0.3048)
			(end 0.120396 0.2794)
			(stroke
				(width 0.1)
				(type default)
			)
			(layer "F.Fab")
		)
		(fp_line
			(start 0.67945 0.3048)
			(end 0.120396 0.3048)
			(stroke
				(width 0.1)
				(type default)
			)
			(layer "F.Fab")
		)
		(fp_line
			(start -0.12065 0.2794)
			(end -0.12065 0.3048)
			(stroke
				(width 0.1)
				(type default)
			)
			(layer "F.Fab")
		)
		(fp_line
			(start 0.120396 0.2794)
			(end -0.12065 0.2794)
			(stroke
				(width 0.1)
				(type default)
			)
			(layer "F.Fab")
		)
		(fp_line
			(start -0.12065 -0.2794)
			(end 0.12065 -0.2794)
			(stroke
				(width 0.1)
				(type default)
			)
			(layer "F.Fab")
		)
		(fp_line
			(start 0.12065 -0.2794)
			(end 0.12065 -0.3048)
			(stroke
				(width 0.1)
				(type default)
			)
			(layer "F.Fab")
		)
		(fp_line
			(start 0.12065 -0.3048)
			(end 0.67945 -0.3048)
			(stroke
				(width 0.1)
				(type default)
			)
			(layer "F.Fab")
		)
		(fp_line
			(start 0.67945 -0.3048)
			(end 0.67945 0.3048)
			(stroke
				(width 0.1)
				(type default)
			)
			(layer "F.Fab")
		)
		(fp_line
			(start -0.67945 -0.305054)
			(end -0.12065 -0.305054)
			(stroke
				(width 0.1)
				(type default)
			)
			(layer "F.Fab")
		)
		(fp_line
			(start -0.12065 -0.305054)
			(end -0.12065 -0.2794)
			(stroke
				(width 0.1)
				(type default)
			)
			(layer "F.Fab")
		)
		(pad "1" smd circle
			(at -0.40005 0 270)
			(size 0 0)
			(layers "F.Cu" "F.Mask" "F.Paste")
			(net "P3V3_AUX")
		)
		(pad "2" smd circle
			(at 0.40005 0 270)
			(size 0 0)
			(layers "F.Cu" "F.Mask" "F.Paste")
			(net "JTAG_BIC_TDO_R")
		)
	)
	(footprint ""
		(layer "F.Cu")
		(at 233.769916 -274.531328 180)
		(property "Reference" "C4335"
			(at 0 0 180)
			(layer "F.SilkS")
			(hide yes)
			(effects
				(font
					(size 1.27 1.27)
				)
			)
		)
		(property "Value" ""
			(at 0 0 180)
			(layer "F.Fab")
			(effects
				(font
					(size 1.27 1.27)
				)
			)
		)
		(duplicate_pad_numbers_are_jumpers no)
		(fp_line
			(start 0.299974 0.150114)
			(end -0.299974 0.150114)
			(stroke
				(width 0.1)
				(type default)
			)
			(layer "F.Fab")
		)
		(fp_line
			(start 0.299974 -0.150114)
			(end 0.299974 0.150114)
			(stroke
				(width 0.1)
				(type default)
			)
			(layer "F.Fab")
		)
		(fp_line
			(start -0.299974 0.150114)
			(end -0.299974 -0.150114)
			(stroke
				(width 0.1)
				(type default)
			)
			(layer "F.Fab")
		)
		(fp_line
			(start -0.299974 -0.150114)
			(end 0.299974 -0.150114)
			(stroke
				(width 0.1)
				(type default)
			)
			(layer "F.Fab")
		)
		(pad "1" smd rect
			(at -0.2667 0 180)
			(size 0.3048 0.381)
			(layers "F.Cu" "F.Mask" "F.Paste")
			(net "P1V25_PEX2")
		)
		(pad "2" smd rect
			(at 0.2667 0 180)
			(size 0.3048 0.381)
			(layers "F.Cu" "F.Mask" "F.Paste")
			(net "GND")
		)
	)
)
